(kicad_pcb
	(version 20260206)
	(generator "pcbnew")
	(generator_version "10.0")
	(general
		(thickness 1.6)
		(legacy_teardrops no)
	)
	(paper "A4")
	(title_block
		(title "04192023_DAF0TMB3IC0_F0TG_MB_C_brd_V02_OCP.brd")
		(comment 1 "Grand Teton / footprints 1525-1531 of 8354")
	)
	(layers
		(0 "F.Cu" signal "TOP")
		(4 "In1.Cu" signal "GND")
		(6 "In2.Cu" signal "IN1")
		(8 "In3.Cu" signal "GND1")
		(10 "In4.Cu" signal "IN2")
		(12 "In5.Cu" signal "GND2")
		(14 "In6.Cu" signal "IN3")
		(16 "In7.Cu" signal "GND3")
		(18 "In8.Cu" signal "VCC")
		(20 "In9.Cu" signal "VCC1")
		(22 "In10.Cu" signal "GND4")
		(24 "In11.Cu" signal "IN4")
		(26 "In12.Cu" signal "GND5")
		(28 "In13.Cu" signal "IN5")
		(30 "In14.Cu" signal "GND6")
		(32 "In15.Cu" signal "IN6")
		(34 "In16.Cu" signal "GND7")
		(2 "B.Cu" signal "BOTTOM")
		(9 "F.Adhes" user "F.Adhesive")
		(11 "B.Adhes" user "B.Adhesive")
		(13 "F.Paste" user "Package Geometry/Pastemask Top")
		(15 "B.Paste" user "Package Geometry/Pastemask Bottom")
		(5 "F.SilkS" user "Ref Des/Silkscreen Top")
		(7 "B.SilkS" user "Ref Des/Silkscreen Bottom")
		(1 "F.Mask" user "Board Geometry/Soldermask Top")
		(3 "B.Mask" user "Board Geometry/Soldermask Bottom")
		(17 "Dwgs.User" user "User.Drawings")
		(19 "Cmts.User" user "User.Comments")
		(21 "Eco1.User" user "User.Eco1")
		(23 "Eco2.User" user "User.Eco2")
		(25 "Edge.Cuts" user "Board Geometry/Outline")
		(27 "Margin" user)
		(31 "F.CrtYd" user "Package Geometry/Place Bound Top")
		(29 "B.CrtYd" user "Package Geometry/Place Bound Bottom")
		(35 "F.Fab" user "Ref Des/Assembly Top")
		(33 "B.Fab" user "Ref Des/Assembly Bottom")
	)
	(footprint ""
		(layer "F.Cu")
		(at 95.494094 -325.675752)
		(property "Reference" "PL45"
			(at -2.657094 -16.689578 0)
			(unlocked yes)
			(layer "F.SilkS")
			(effects
				(font
					(size 0.7874 0.5842)
					(thickness 0.1524)
				)
				(justify left)
			)
		)
		(property "Value" ""
			(at 0 0 0)
			(layer "F.Fab")
			(effects
				(font
					(size 1.27 1.27)
				)
			)
		)
		(duplicate_pad_numbers_are_jumpers no)
		(fp_line
			(start -3.750056 -5.500116)
			(end -2.393442 -5.500116)
			(stroke
				(width 0.1524)
				(type default)
			)
			(layer "F.SilkS")
		)
		(fp_line
			(start -3.750056 5.500116)
			(end -3.750056 -5.500116)
			(stroke
				(width 0.1524)
				(type default)
			)
			(layer "F.SilkS")
		)
		(fp_line
			(start -2.393442 5.500116)
			(end -3.750056 5.500116)
			(stroke
				(width 0.1524)
				(type default)
			)
			(layer "F.SilkS")
		)
		(fp_line
			(start 2.393442 5.500116)
			(end 3.750056 5.500116)
			(stroke
				(width 0.1524)
				(type default)
			)
			(layer "F.SilkS")
		)
		(fp_line
			(start 3.750056 -5.500116)
			(end 2.393442 -5.500116)
			(stroke
				(width 0.1524)
				(type default)
			)
			(layer "F.SilkS")
		)
		(fp_line
			(start 3.750056 5.500116)
			(end 3.750056 -5.500116)
			(stroke
				(width 0.1524)
				(type default)
			)
			(layer "F.SilkS")
		)
		(fp_poly
			(pts
				(xy -3.9116 -4.249928) (xy -4.3434 -4.034028) (xy -4.3434 -4.465828)
			)
			(stroke
				(width 0)
				(type default)
			)
			(fill yes)
			(layer "F.SilkS")
		)
		(fp_line
			(start -3.750056 -5.500116)
			(end -3.750056 5.500116)
			(stroke
				(width 0.1)
				(type default)
			)
			(layer "F.Fab")
		)
		(fp_line
			(start -3.750056 5.500116)
			(end 3.750056 5.500116)
			(stroke
				(width 0.1)
				(type default)
			)
			(layer "F.Fab")
		)
		(fp_line
			(start 3.750056 -5.500116)
			(end -3.750056 -5.500116)
			(stroke
				(width 0.1)
				(type default)
			)
			(layer "F.Fab")
		)
		(fp_line
			(start 3.750056 5.500116)
			(end 3.750056 -5.500116)
			(stroke
				(width 0.1)
				(type default)
			)
			(layer "F.Fab")
		)
		(fp_poly
			(pts
				(xy -4.9276 -4.757928) (xy -4.9276 -3.741928) (xy -3.9116 -4.249928)
			)
			(stroke
				(width 0)
				(type default)
			)
			(fill yes)
			(layer "F.Fab")
		)
		(pad "1" smd rect
			(at 0 -4.249928 270)
			(size 2.413 4.5212)
			(layers "F.Cu" "F.Mask" "F.Paste")
			(net "SW_PVDDCR_CPU1_P1_SW5")
		)
		(pad "2" smd rect
			(at 0 -1.175004 270)
			(size 1.3716 4.5212)
			(layers "F.Cu" "F.Mask" "F.Paste")
			(net "IND_CPU1_P1_CPL6")
		)
		(pad "3" smd rect
			(at 0 1.175004 270)
			(size 1.3716 4.5212)
			(layers "F.Cu" "F.Mask" "F.Paste")
			(net "IND_CPU1_P1_CPL5")
		)
		(pad "4" smd rect
			(at 0 4.249928 270)
			(size 2.413 4.5212)
			(layers "F.Cu" "F.Mask" "F.Paste")
			(net "PVDDCR_CPU1_P1")
		)
	)
	(footprint ""
		(layer "F.Cu")
		(at 450.717666 -401.93087 180)
		(property "Reference" "PC6576"
			(at 0 0 180)
			(layer "F.SilkS")
			(hide yes)
			(effects
				(font
					(size 1.27 1.27)
				)
			)
		)
		(property "Value" ""
			(at 0 0 180)
			(layer "F.Fab")
			(effects
				(font
					(size 1.27 1.27)
				)
			)
		)
		(duplicate_pad_numbers_are_jumpers no)
		(fp_line
			(start 0.7874 0.4064)
			(end -0.7874 0.4064)
			(stroke
				(width 0.1524)
				(type default)
			)
			(layer "F.SilkS")
		)
		(fp_line
			(start 0.7874 -0.4064)
			(end 0.7874 0.4064)
			(stroke
				(width 0.1524)
				(type default)
			)
			(layer "F.SilkS")
		)
		(fp_line
			(start -0.7874 0.4064)
			(end -0.7874 -0.4064)
			(stroke
				(width 0.1524)
				(type default)
			)
			(layer "F.SilkS")
		)
		(fp_line
			(start -0.7874 -0.4064)
			(end 0.7874 -0.4064)
			(stroke
				(width 0.1524)
				(type default)
			)
			(layer "F.SilkS")
		)
		(fp_line
			(start 0.67945 0.3048)
			(end 0.120396 0.3048)
			(stroke
				(width 0.1)
				(type default)
			)
			(layer "F.Fab")
		)
		(fp_line
			(start 0.67945 -0.3048)
			(end 0.67945 0.3048)
			(stroke
				(width 0.1)
				(type default)
			)
			(layer "F.Fab")
		)
		(fp_line
			(start 0.12065 -0.2794)
			(end 0.12065 -0.3048)
			(stroke
				(width 0.1)
				(type default)
			)
			(layer "F.Fab")
		)
		(fp_line
			(start 0.12065 -0.3048)
			(end 0.67945 -0.3048)
			(stroke
				(width 0.1)
				(type default)
			)
			(layer "F.Fab")
		)
		(fp_line
			(start 0.120396 0.3048)
			(end 0.120396 0.2794)
			(stroke
				(width 0.1)
				(type default)
			)
			(layer "F.Fab")
		)
		(fp_line
			(start 0.120396 0.2794)
			(end -0.12065 0.2794)
			(stroke
				(width 0.1)
				(type default)
			)
			(layer "F.Fab")
		)
		(fp_line
			(start -0.12065 0.3048)
			(end -0.67945 0.3048)
			(stroke
				(width 0.1)
				(type default)
			)
			(layer "F.Fab")
		)
		(fp_line
			(start -0.12065 0.2794)
			(end -0.12065 0.3048)
			(stroke
				(width 0.1)
				(type default)
			)
			(layer "F.Fab")
		)
		(fp_line
			(start -0.12065 -0.2794)
			(end 0.12065 -0.2794)
			(stroke
				(width 0.1)
				(type default)
			)
			(layer "F.Fab")
		)
		(fp_line
			(start -0.12065 -0.305054)
			(end -0.12065 -0.2794)
			(stroke
				(width 0.1)
				(type default)
			)
			(layer "F.Fab")
		)
		(fp_line
			(start -0.67945 0.3048)
			(end -0.67945 -0.305054)
			(stroke
				(width 0.1)
				(type default)
			)
			(layer "F.Fab")
		)
		(fp_line
			(start -0.67945 -0.305054)
			(end -0.12065 -0.305054)
			(stroke
				(width 0.1)
				(type default)
			)
			(layer "F.Fab")
		)
		(pad "1" smd circle
			(at -0.40005 0 180)
			(size 0 0)
			(layers "F.Cu" "F.Mask" "F.Paste")
			(net "PV09_RETIMER_CPU0_VCCS")
		)
		(pad "2" smd circle
			(at 0.40005 0 180)
			(size 0 0)
			(layers "F.Cu" "F.Mask" "F.Paste")
			(net "GND")
		)
	)
	(footprint ""
		(layer "F.Cu")
		(at 357.515922 -256.012188 90)
		(property "Reference" "C3930"
			(at 0 0 90)
			(layer "F.SilkS")
			(hide yes)
			(effects
				(font
					(size 1.27 1.27)
				)
			)
		)
		(property "Value" ""
			(at 0 0 90)
			(layer "F.Fab")
			(effects
				(font
					(size 1.27 1.27)
				)
			)
		)
		(duplicate_pad_numbers_are_jumpers no)
		(fp_line
			(start 0.7874 -0.4064)
			(end 0.7874 0.4064)
			(stroke
				(width 0.1524)
				(type default)
			)
			(layer "F.SilkS")
		)
		(fp_line
			(start -0.7874 -0.4064)
			(end 0.7874 -0.4064)
			(stroke
				(width 0.1524)
				(type default)
			)
			(layer "F.SilkS")
		)
		(fp_line
			(start 0.7874 0.4064)
			(end -0.7874 0.4064)
			(stroke
				(width 0.1524)
				(type default)
			)
			(layer "F.SilkS")
		)
		(fp_line
			(start -0.7874 0.4064)
			(end -0.7874 -0.4064)
			(stroke
				(width 0.1524)
				(type default)
			)
			(layer "F.SilkS")
		)
		(fp_line
			(start -0.12065 -0.305054)
			(end -0.12065 -0.2794)
			(stroke
				(width 0.1)
				(type default)
			)
			(layer "F.Fab")
		)
		(fp_line
			(start -0.67945 -0.305054)
			(end -0.12065 -0.305054)
			(stroke
				(width 0.1)
				(type default)
			)
			(layer "F.Fab")
		)
		(fp_line
			(start 0.67945 -0.3048)
			(end 0.67945 0.3048)
			(stroke
				(width 0.1)
				(type default)
			)
			(layer "F.Fab")
		)
		(fp_line
			(start 0.12065 -0.3048)
			(end 0.67945 -0.3048)
			(stroke
				(width 0.1)
				(type default)
			)
			(layer "F.Fab")
		)
		(fp_line
			(start 0.12065 -0.2794)
			(end 0.12065 -0.3048)
			(stroke
				(width 0.1)
				(type default)
			)
			(layer "F.Fab")
		)
		(fp_line
			(start -0.12065 -0.2794)
			(end 0.12065 -0.2794)
			(stroke
				(width 0.1)
				(type default)
			)
			(layer "F.Fab")
		)
		(fp_line
			(start 0.120396 0.2794)
			(end -0.12065 0.2794)
			(stroke
				(width 0.1)
				(type default)
			)
			(layer "F.Fab")
		)
		(fp_line
			(start -0.12065 0.2794)
			(end -0.12065 0.3048)
			(stroke
				(width 0.1)
				(type default)
			)
			(layer "F.Fab")
		)
		(fp_line
			(start 0.67945 0.3048)
			(end 0.120396 0.3048)
			(stroke
				(width 0.1)
				(type default)
			)
			(layer "F.Fab")
		)
		(fp_line
			(start 0.120396 0.3048)
			(end 0.120396 0.2794)
			(stroke
				(width 0.1)
				(type default)
			)
			(layer "F.Fab")
		)
		(fp_line
			(start -0.12065 0.3048)
			(end -0.67945 0.3048)
			(stroke
				(width 0.1)
				(type default)
			)
			(layer "F.Fab")
		)
		(fp_line
			(start -0.67945 0.3048)
			(end -0.67945 -0.305054)
			(stroke
				(width 0.1)
				(type default)
			)
			(layer "F.Fab")
		)
		(pad "1" smd circle
			(at -0.40005 0 90)
			(size 0 0)
			(layers "F.Cu" "F.Mask" "F.Paste")
			(net "PVDDCR_SOC_P0")
		)
		(pad "2" smd circle
			(at 0.40005 0 90)
			(size 0 0)
			(layers "F.Cu" "F.Mask" "F.Paste")
			(net "GND")
		)
	)
	(footprint ""
		(layer "F.Cu")
		(at 75.05573 -387.764274)
		(property "Reference" "R597"
			(at 0 0 0)
			(layer "F.SilkS")
			(hide yes)
			(effects
				(font
					(size 1.27 1.27)
				)
			)
		)
		(property "Value" ""
			(at 0 0 0)
			(layer "F.Fab")
			(effects
				(font
					(size 1.27 1.27)
				)
			)
		)
		(duplicate_pad_numbers_are_jumpers no)
		(fp_line
			(start -0.32512 -0.175006)
			(end 0.32512 -0.175006)
			(stroke
				(width 0.1)
				(type default)
			)
			(layer "F.Fab")
		)
		(fp_line
			(start -0.32512 0.175006)
			(end -0.32512 -0.175006)
			(stroke
				(width 0.1)
				(type default)
			)
			(layer "F.Fab")
		)
		(fp_line
			(start 0.32512 -0.175006)
			(end 0.32512 0.175006)
			(stroke
				(width 0.1)
				(type default)
			)
			(layer "F.Fab")
		)
		(fp_line
			(start 0.32512 0.175006)
			(end -0.32512 0.175006)
			(stroke
				(width 0.1)
				(type default)
			)
			(layer "F.Fab")
		)
		(pad "1" smd rect
			(at -0.2667 0)
			(size 0.3048 0.381)
			(layers "F.Cu" "F.Mask" "F.Paste")
			(net "CLK_100M_RETIMER_CPU1_P1_R_DP")
		)
		(pad "2" smd rect
			(at 0.2667 0 180)
			(size 0.3048 0.381)
			(layers "F.Cu" "F.Mask" "F.Paste")
			(net "CLK_100M_RETIMER_CPU1_P1_DP")
		)
	)
	(footprint ""
		(layer "F.Cu")
		(at 239.50803 -48.019208 180)
		(property "Reference" "R3779"
			(at 0 0 180)
			(layer "F.SilkS")
			(hide yes)
			(effects
				(font
					(size 1.27 1.27)
				)
			)
		)
		(property "Value" ""
			(at 0 0 180)
			(layer "F.Fab")
			(effects
				(font
					(size 1.27 1.27)
				)
			)
		)
		(duplicate_pad_numbers_are_jumpers no)
		(fp_line
			(start 0.7874 0.4064)
			(end -0.7874 0.4064)
			(stroke
				(width 0.1524)
				(type default)
			)
			(layer "F.SilkS")
		)
		(fp_line
			(start 0.7874 -0.4064)
			(end 0.7874 0.4064)
			(stroke
				(width 0.1524)
				(type default)
			)
			(layer "F.SilkS")
		)
		(fp_line
			(start -0.7874 0.4064)
			(end -0.7874 -0.4064)
			(stroke
				(width 0.1524)
				(type default)
			)
			(layer "F.SilkS")
		)
		(fp_line
			(start -0.7874 -0.4064)
			(end 0.7874 -0.4064)
			(stroke
				(width 0.1524)
				(type default)
			)
			(layer "F.SilkS")
		)
		(fp_line
			(start 0.67945 0.3048)
			(end 0.120396 0.3048)
			(stroke
				(width 0.1)
				(type default)
			)
			(layer "F.Fab")
		)
		(fp_line
			(start 0.67945 -0.3048)
			(end 0.67945 0.3048)
			(stroke
				(width 0.1)
				(type default)
			)
			(layer "F.Fab")
		)
		(fp_line
			(start 0.12065 -0.2794)
			(end 0.12065 -0.3048)
			(stroke
				(width 0.1)
				(type default)
			)
			(layer "F.Fab")
		)
		(fp_line
			(start 0.12065 -0.3048)
			(end 0.67945 -0.3048)
			(stroke
				(width 0.1)
				(type default)
			)
			(layer "F.Fab")
		)
		(fp_line
			(start 0.120396 0.3048)
			(end 0.120396 0.2794)
			(stroke
				(width 0.1)
				(type default)
			)
			(layer "F.Fab")
		)
		(fp_line
			(start 0.120396 0.2794)
			(end -0.12065 0.2794)
			(stroke
				(width 0.1)
				(type default)
			)
			(layer "F.Fab")
		)
		(fp_line
			(start -0.12065 0.3048)
			(end -0.67945 0.3048)
			(stroke
				(width 0.1)
				(type default)
			)
			(layer "F.Fab")
		)
		(fp_line
			(start -0.12065 0.2794)
			(end -0.12065 0.3048)
			(stroke
				(width 0.1)
				(type default)
			)
			(layer "F.Fab")
		)
		(fp_line
			(start -0.12065 -0.2794)
			(end 0.12065 -0.2794)
			(stroke
				(width 0.1)
				(type default)
			)
			(layer "F.Fab")
		)
		(fp_line
			(start -0.12065 -0.305054)
			(end -0.12065 -0.2794)
			(stroke
				(width 0.1)
				(type default)
			)
			(layer "F.Fab")
		)
		(fp_line
			(start -0.67945 0.3048)
			(end -0.67945 -0.305054)
			(stroke
				(width 0.1)
				(type default)
			)
			(layer "F.Fab")
		)
		(fp_line
			(start -0.67945 -0.305054)
			(end -0.12065 -0.305054)
			(stroke
				(width 0.1)
				(type default)
			)
			(layer "F.Fab")
		)
		(pad "1" smd circle
			(at -0.40005 0 180)
			(size 0 0)
			(layers "F.Cu" "F.Mask" "F.Paste")
			(net "RST_PERST_E1S_0_N")
		)
		(pad "2" smd circle
			(at 0.40005 0 180)
			(size 0 0)
			(layers "F.Cu" "F.Mask" "F.Paste")
			(net "RST_PCIE_E1S_PERST_N")
		)
	)
	(footprint ""
		(layer "F.Cu")
		(at 60.012834 -150.979632 180)
		(property "Reference" "PL57"
			(at -1.85674 -6.476746 0)
			(unlocked yes)
			(layer "F.SilkS")
			(effects
				(font
					(size 0.7874 0.5842)
					(thickness 0.1524)
				)
				(justify left)
			)
		)
		(property "Value" ""
			(at 0 0 180)
			(layer "F.Fab")
			(effects
				(font
					(size 1.27 1.27)
				)
			)
		)
		(duplicate_pad_numbers_are_jumpers no)
		(fp_line
			(start 5.1054 5.100066)
			(end 5.1054 1.8796)
			(stroke
				(width 0.1524)
				(type default)
			)
			(layer "F.SilkS")
		)
		(fp_line
			(start 5.1054 -1.8796)
			(end 5.1054 -5.100066)
			(stroke
				(width 0.1524)
				(type default)
			)
			(layer "F.SilkS")
		)
		(fp_line
			(start 5.1054 -5.100066)
			(end -5.1054 -5.100066)
			(stroke
				(width 0.1524)
				(type default)
			)
			(layer "F.SilkS")
		)
		(fp_line
			(start -5.1054 5.100066)
			(end 5.1054 5.100066)
			(stroke
				(width 0.1524)
				(type default)
			)
			(layer "F.SilkS")
		)
		(fp_line
			(start -5.1054 1.8796)
			(end -5.1054 5.100066)
			(stroke
				(width 0.1524)
				(type default)
			)
			(layer "F.SilkS")
		)
		(fp_line
			(start -5.1054 -5.100066)
			(end -5.1054 -1.8796)
			(stroke
				(width 0.1524)
				(type default)
			)
			(layer "F.SilkS")
		)
		(fp_line
			(start 5.1054 5.100066)
			(end -5.1054 5.100066)
			(stroke
				(width 0.1)
				(type default)
			)
			(layer "F.Fab")
		)
		(fp_line
			(start 5.1054 -5.100066)
			(end 5.1054 5.100066)
			(stroke
				(width 0.1)
				(type default)
			)
			(layer "F.Fab")
		)
		(fp_line
			(start -5.1054 5.100066)
			(end -5.1054 -5.100066)
			(stroke
				(width 0.1)
				(type default)
			)
			(layer "F.Fab")
		)
		(fp_line
			(start -5.1054 -5.100066)
			(end 5.1054 -5.100066)
			(stroke
				(width 0.1)
				(type default)
			)
			(layer "F.Fab")
		)
		(pad "1" smd rect
			(at -3.999992 0 180)
			(size 3.5052 3.5052)
			(layers "F.Cu" "F.Mask" "F.Paste")
			(net "SW_PVDD18_S5_P1_SW")
		)
		(pad "2" smd rect
			(at 3.999992 0 180)
			(size 3.5052 3.5052)
			(layers "F.Cu" "F.Mask" "F.Paste")
			(net "PVDD18_S5_P1")
		)
	)
	(footprint ""
		(layer "F.Cu")
		(at 215.4301 -399.956782)
		(property "Reference" "PR3921"
			(at 0 0 0)
			(layer "F.SilkS")
			(hide yes)
			(effects
				(font
					(size 1.27 1.27)
				)
			)
		)
		(property "Value" ""
			(at 0 0 0)
			(layer "F.Fab")
			(effects
				(font
					(size 1.27 1.27)
				)
			)
		)
		(duplicate_pad_numbers_are_jumpers no)
		(fp_line
			(start -0.7874 -0.4064)
			(end 0.7874 -0.4064)
			(stroke
				(width 0.1524)
				(type default)
			)
			(layer "F.SilkS")
		)
		(fp_line
			(start -0.7874 0.4064)
			(end -0.7874 -0.4064)
			(stroke
				(width 0.1524)
				(type default)
			)
			(layer "F.SilkS")
		)
		(fp_line
			(start 0.7874 -0.4064)
			(end 0.7874 0.4064)
			(stroke
				(width 0.1524)
				(type default)
			)
			(layer "F.SilkS")
		)
		(fp_line
			(start 0.7874 0.4064)
			(end -0.7874 0.4064)
			(stroke
				(width 0.1524)
				(type default)
			)
			(layer "F.SilkS")
		)
		(fp_line
			(start -0.67945 -0.305054)
			(end -0.12065 -0.305054)
			(stroke
				(width 0.1)
				(type default)
			)
			(layer "F.Fab")
		)
		(fp_line
			(start -0.67945 0.3048)
			(end -0.67945 -0.305054)
			(stroke
				(width 0.1)
				(type default)
			)
			(layer "F.Fab")
		)
		(fp_line
			(start -0.12065 -0.305054)
			(end -0.12065 -0.2794)
			(stroke
				(width 0.1)
				(type default)
			)
			(layer "F.Fab")
		)
		(fp_line
			(start -0.12065 -0.2794)
			(end 0.12065 -0.2794)
			(stroke
				(width 0.1)
				(type default)
			)
			(layer "F.Fab")
		)
		(fp_line
			(start -0.12065 0.2794)
			(end -0.12065 0.3048)
			(stroke
				(width 0.1)
				(type default)
			)
			(layer "F.Fab")
		)
		(fp_line
			(start -0.12065 0.3048)
			(end -0.67945 0.3048)
			(stroke
				(width 0.1)
				(type default)
			)
			(layer "F.Fab")
		)
		(fp_line
			(start 0.120396 0.2794)
			(end -0.12065 0.2794)
			(stroke
				(width 0.1)
				(type default)
			)
			(layer "F.Fab")
		)
		(fp_line
			(start 0.120396 0.3048)
			(end 0.120396 0.2794)
			(stroke
				(width 0.1)
				(type default)
			)
			(layer "F.Fab")
		)
		(fp_line
			(start 0.12065 -0.3048)
			(end 0.67945 -0.3048)
			(stroke
				(width 0.1)
				(type default)
			)
			(layer "F.Fab")
		)
		(fp_line
			(start 0.12065 -0.2794)
			(end 0.12065 -0.3048)
			(stroke
				(width 0.1)
				(type default)
			)
			(layer "F.Fab")
		)
		(fp_line
			(start 0.67945 -0.3048)
			(end 0.67945 0.3048)
			(stroke
				(width 0.1)
				(type default)
			)
			(layer "F.Fab")
		)
		(fp_line
			(start 0.67945 0.3048)
			(end 0.120396 0.3048)
			(stroke
				(width 0.1)
				(type default)
			)
			(layer "F.Fab")
		)
		(pad "1" smd circle
			(at -0.40005 0)
			(size 0 0)
			(layers "F.Cu" "F.Mask" "F.Paste")
			(net "HSC_D_OC_2")
		)
		(pad "2" smd circle
			(at 0.40005 0)
			(size 0 0)
			(layers "F.Cu" "F.Mask" "F.Paste")
			(net "HSC_D_OC_R")
		)
	)
)
